(kicad_pcb
	(version 20260206)
	(generator "pcbnew")
	(generator_version "10.0")
	(general
		(thickness 1.6)
		(legacy_teardrops no)
	)
	(paper "A4")
	(title_block
		(title "01162023_DA0F0TEBIF0_F0T_Expander_BD_F_brd_V02_OCP.brd")
		(comment 1 "Grand Teton / footprints 8759-8764 of 9728")
	)
	(layers
		(0 "F.Cu" signal "TOP")
		(4 "In1.Cu" signal "GND")
		(6 "In2.Cu" signal "VCC")
		(8 "In3.Cu" signal "VCC1")
		(10 "In4.Cu" signal "GND1")
		(12 "In5.Cu" signal "IN1")
		(14 "In6.Cu" signal "GND2")
		(16 "In7.Cu" signal "IN2")
		(18 "In8.Cu" signal "GND3")
		(20 "In9.Cu" signal "IN3")
		(22 "In10.Cu" signal "GND4")
		(24 "In11.Cu" signal "IN4")
		(26 "In12.Cu" signal "GND5")
		(28 "In13.Cu" signal "IN5")
		(30 "In14.Cu" signal "GND6")
		(32 "In15.Cu" signal "IN6")
		(34 "In16.Cu" signal "GND7")
		(2 "B.Cu" signal "BOTTOM")
		(9 "F.Adhes" user "F.Adhesive")
		(11 "B.Adhes" user "B.Adhesive")
		(13 "F.Paste" user "Package Geometry/Pastemask Top")
		(15 "B.Paste" user "Package Geometry/Pastemask Bottom")
		(5 "F.SilkS" user "Ref Des/Silkscreen Top")
		(7 "B.SilkS" user "Ref Des/Silkscreen Bottom")
		(1 "F.Mask" user "Board Geometry/Soldermask Top")
		(3 "B.Mask" user "Board Geometry/Soldermask Bottom")
		(17 "Dwgs.User" user "User.Drawings")
		(19 "Cmts.User" user "User.Comments")
		(21 "Eco1.User" user "User.Eco1")
		(23 "Eco2.User" user "User.Eco2")
		(25 "Edge.Cuts" user "Board Geometry/Outline")
		(27 "Margin" user)
		(31 "F.CrtYd" user "Package Geometry/Place Bound Top")
		(29 "B.CrtYd" user "Package Geometry/Place Bound Bottom")
		(35 "F.Fab" user "Ref Des/Assembly Top")
		(33 "B.Fab" user "Ref Des/Assembly Bottom")
	)
	(footprint ""
		(layer "B.Cu")
		(at 232.960164 -459.85049)
		(property "Reference" "X75"
			(at 0.1778 -1.92913 0)
			(unlocked yes)
			(layer "B.SilkS")
			(effects
				(font
					(size 0.7874 0.5842)
					(thickness 0.1524)
				)
				(justify left mirror)
			)
		)
		(property "Value" ""
			(at 0 0 0)
			(layer "B.Fab")
			(effects
				(font
					(size 1.27 1.27)
				)
				(justify mirror)
			)
		)
		(property "Device Type" "TP_TDR_4P_FTS_MPKT4_H025P0200_IO_TP15_TP_TDR_4P_DIP"
			(at -1.30175 1.27 270)
			(unlocked yes)
			(layer "B.Fab")
			(hide yes)
			(effects
				(font
					(size 0.635 0.4064)
					(thickness 0.1524)
				)
				(justify mirror)
			)
		)
		(property "User Part Number" "TP15"
			(at -1.30175 1.27 270)
			(unlocked yes)
			(layer "Cmts.User")
			(hide yes)
			(effects
				(font
					(size 0.635 0.4064)
					(thickness 0.1524)
				)
				(justify mirror)
			)
		)
		(duplicate_pad_numbers_are_jumpers no)
		(fp_line
			(start -2.54 -1.27)
			(end 0 -1.27)
			(stroke
				(width 0.1524)
				(type default)
			)
			(layer "B.SilkS")
		)
		(fp_line
			(start -2.54 -1.1303)
			(end -2.54 -1.27)
			(stroke
				(width 0.1524)
				(type default)
			)
			(layer "B.SilkS")
		)
		(fp_line
			(start -2.54 1.4097)
			(end -2.54 1.1303)
			(stroke
				(width 0.1524)
				(type default)
			)
			(layer "B.SilkS")
		)
		(fp_line
			(start -2.54 3.81)
			(end -2.54 3.6703)
			(stroke
				(width 0.1524)
				(type default)
			)
			(layer "B.SilkS")
		)
		(fp_line
			(start 0 -1.27)
			(end 0 -0.635)
			(stroke
				(width 0.1524)
				(type default)
			)
			(layer "B.SilkS")
		)
		(fp_line
			(start 0 0.635)
			(end 0 1.905)
			(stroke
				(width 0.1524)
				(type default)
			)
			(layer "B.SilkS")
		)
		(fp_line
			(start 0 3.175)
			(end 0 3.81)
			(stroke
				(width 0.1524)
				(type default)
			)
			(layer "B.SilkS")
		)
		(fp_line
			(start 0 3.81)
			(end -2.54 3.81)
			(stroke
				(width 0.1524)
				(type default)
			)
			(layer "B.SilkS")
		)
		(fp_poly
			(pts
				(xy 0.761746 0) (xy 2.285746 -0.762) (xy 2.285746 0.762)
			)
			(stroke
				(width 0)
				(type default)
			)
			(fill yes)
			(layer "B.SilkS")
		)
		(fp_line
			(start -2.54 -1.27)
			(end 0 -1.27)
			(stroke
				(width 0.1)
				(type default)
			)
			(layer "B.Fab")
		)
		(fp_line
			(start -2.54 3.81)
			(end -2.54 -1.27)
			(stroke
				(width 0.1)
				(type default)
			)
			(layer "B.Fab")
		)
		(fp_line
			(start 0 -1.27)
			(end 0 3.81)
			(stroke
				(width 0.1)
				(type default)
			)
			(layer "B.Fab")
		)
		(fp_line
			(start 0 3.81)
			(end -2.54 3.81)
			(stroke
				(width 0.1)
				(type default)
			)
			(layer "B.Fab")
		)
		(fp_poly
			(pts
				(xy 0.761746 0) (xy 2.285746 -0.762) (xy 2.285746 0.762)
			)
			(stroke
				(width 0)
				(type default)
			)
			(fill yes)
			(layer "B.Fab")
		)
		(pad "1" thru_hole circle
			(at 0 0 180)
			(size 1.0033 1.0033)
			(drill 0.249936)
			(layers "*.Cu" "*.Mask")
			(remove_unused_layers no)
			(net "TDR_DIFF_100_IN4_DIN")
			(clearance 0.10795)
			(padstack
				(mode front_inner_back)
				(layer "Inner"
					(shape circle)
					(size 0.8001 0.8001)
					(clearance 0.1524)
				)
				(layer "B.Cu"
					(shape circle)
					(size 1.0033 1.0033)
					(thermal_gap 0.10795)
					(clearance 0.10795)
				)
			)
		)
		(pad "2" thru_hole circle
			(at -2.54 0 180)
			(size 1.9939 1.9939)
			(drill 0.249936)
			(layers "*.Cu" "*.Mask")
			(remove_unused_layers no)
			(net "COUPON_GND1")
			(clearance 0.10795)
			(padstack
				(mode front_inner_back)
				(layer "Inner"
					(shape circle)
					(size 0.8001 0.8001)
					(clearance 0.1524)
				)
				(layer "B.Cu"
					(shape circle)
					(size 1.9939 1.9939)
					(thermal_gap 0.10795)
					(clearance 0.10795)
				)
			)
		)
		(pad "3" thru_hole circle
			(at -2.54 2.54 180)
			(size 1.9939 1.9939)
			(drill 0.249936)
			(layers "*.Cu" "*.Mask")
			(remove_unused_layers no)
			(net "COUPON_GND1")
			(clearance 0.10795)
			(padstack
				(mode front_inner_back)
				(layer "Inner"
					(shape circle)
					(size 0.8001 0.8001)
					(clearance 0.1524)
				)
				(layer "B.Cu"
					(shape circle)
					(size 1.9939 1.9939)
					(thermal_gap 0.10795)
					(clearance 0.10795)
				)
			)
		)
		(pad "4" thru_hole circle
			(at 0 2.54 180)
			(size 1.0033 1.0033)
			(drill 0.249936)
			(layers "*.Cu" "*.Mask")
			(remove_unused_layers no)
			(net "TDR_DIFF_100_IN4_DIP")
			(clearance 0.10795)
			(padstack
				(mode front_inner_back)
				(layer "Inner"
					(shape circle)
					(size 0.8001 0.8001)
					(clearance 0.1524)
				)
				(layer "B.Cu"
					(shape circle)
					(size 1.0033 1.0033)
					(thermal_gap 0.10795)
					(clearance 0.10795)
				)
			)
		)
	)
	(footprint ""
		(layer "B.Cu")
		(at 212.09 -207.899 90)
		(property "Reference" "R1514"
			(at 0 0 90)
			(layer "B.SilkS")
			(hide yes)
			(effects
				(font
					(size 1.27 1.27)
				)
				(justify mirror)
			)
		)
		(property "Value" ""
			(at 0 0 90)
			(layer "B.Fab")
			(effects
				(font
					(size 1.27 1.27)
				)
				(justify mirror)
			)
		)
		(duplicate_pad_numbers_are_jumpers no)
		(fp_line
			(start 0.7874 -0.4064)
			(end -0.7874 -0.4064)
			(stroke
				(width 0.1524)
				(type default)
			)
			(layer "B.SilkS")
		)
		(fp_line
			(start -0.7874 -0.4064)
			(end -0.7874 0.4064)
			(stroke
				(width 0.1524)
				(type default)
			)
			(layer "B.SilkS")
		)
		(fp_line
			(start 0.7874 0.4064)
			(end 0.7874 -0.4064)
			(stroke
				(width 0.1524)
				(type default)
			)
			(layer "B.SilkS")
		)
		(fp_line
			(start -0.7874 0.4064)
			(end 0.7874 0.4064)
			(stroke
				(width 0.1524)
				(type default)
			)
			(layer "B.SilkS")
		)
		(fp_line
			(start 0.67945 -0.305054)
			(end 0.12065 -0.305054)
			(stroke
				(width 0.1)
				(type default)
			)
			(layer "B.Fab")
		)
		(fp_line
			(start 0.12065 -0.305054)
			(end 0.12065 -0.2794)
			(stroke
				(width 0.1)
				(type default)
			)
			(layer "B.Fab")
		)
		(fp_line
			(start -0.12065 -0.3048)
			(end -0.67945 -0.3048)
			(stroke
				(width 0.1)
				(type default)
			)
			(layer "B.Fab")
		)
		(fp_line
			(start -0.67945 -0.3048)
			(end -0.67945 0.3048)
			(stroke
				(width 0.1)
				(type default)
			)
			(layer "B.Fab")
		)
		(fp_line
			(start 0.12065 -0.2794)
			(end -0.12065 -0.2794)
			(stroke
				(width 0.1)
				(type default)
			)
			(layer "B.Fab")
		)
		(fp_line
			(start -0.12065 -0.2794)
			(end -0.12065 -0.3048)
			(stroke
				(width 0.1)
				(type default)
			)
			(layer "B.Fab")
		)
		(fp_line
			(start 0.12065 0.2794)
			(end 0.12065 0.3048)
			(stroke
				(width 0.1)
				(type default)
			)
			(layer "B.Fab")
		)
		(fp_line
			(start -0.120396 0.2794)
			(end 0.12065 0.2794)
			(stroke
				(width 0.1)
				(type default)
			)
			(layer "B.Fab")
		)
		(fp_line
			(start 0.67945 0.3048)
			(end 0.67945 -0.305054)
			(stroke
				(width 0.1)
				(type default)
			)
			(layer "B.Fab")
		)
		(fp_line
			(start 0.12065 0.3048)
			(end 0.67945 0.3048)
			(stroke
				(width 0.1)
				(type default)
			)
			(layer "B.Fab")
		)
		(fp_line
			(start -0.120396 0.3048)
			(end -0.120396 0.2794)
			(stroke
				(width 0.1)
				(type default)
			)
			(layer "B.Fab")
		)
		(fp_line
			(start -0.67945 0.3048)
			(end -0.120396 0.3048)
			(stroke
				(width 0.1)
				(type default)
			)
			(layer "B.Fab")
		)
		(pad "1" smd circle
			(at 0.40005 0 270)
			(size 0 0)
			(layers "B.Cu" "B.Mask" "B.Paste")
			(net "SMB_NIC4_LS_R_SDA")
		)
		(pad "2" smd circle
			(at -0.40005 0 270)
			(size 0 0)
			(layers "B.Cu" "B.Mask" "B.Paste")
			(net "SMB_NIC4_R_SDA")
		)
	)
	(footprint ""
		(layer "B.Cu")
		(at 119.722392 -308.580028 90)
		(property "Reference" "C1413"
			(at 0 0 90)
			(layer "B.SilkS")
			(hide yes)
			(effects
				(font
					(size 1.27 1.27)
				)
				(justify mirror)
			)
		)
		(property "Value" ""
			(at 0 0 90)
			(layer "B.Fab")
			(effects
				(font
					(size 1.27 1.27)
				)
				(justify mirror)
			)
		)
		(duplicate_pad_numbers_are_jumpers no)
		(fp_line
			(start 1.2954 -0.5842)
			(end -1.2954 -0.5842)
			(stroke
				(width 0.1524)
				(type default)
			)
			(layer "B.SilkS")
		)
		(fp_line
			(start -1.2954 -0.5842)
			(end -1.2954 0.5842)
			(stroke
				(width 0.1524)
				(type default)
			)
			(layer "B.SilkS")
		)
		(fp_line
			(start 1.2954 0.5842)
			(end 1.2954 -0.5842)
			(stroke
				(width 0.1524)
				(type default)
			)
			(layer "B.SilkS")
		)
		(fp_line
			(start -1.2954 0.5842)
			(end 1.2954 0.5842)
			(stroke
				(width 0.1524)
				(type default)
			)
			(layer "B.SilkS")
		)
		(fp_line
			(start 0.8636 -0.4572)
			(end -0.8636 -0.4572)
			(stroke
				(width 0.1)
				(type default)
			)
			(layer "B.Fab")
		)
		(fp_line
			(start -0.8636 -0.4572)
			(end -0.8636 -0.4064)
			(stroke
				(width 0.1)
				(type default)
			)
			(layer "B.Fab")
		)
		(fp_line
			(start 1.1938 -0.4064)
			(end 0.8636 -0.4064)
			(stroke
				(width 0.1)
				(type default)
			)
			(layer "B.Fab")
		)
		(fp_line
			(start 0.8636 -0.4064)
			(end 0.8636 -0.4572)
			(stroke
				(width 0.1)
				(type default)
			)
			(layer "B.Fab")
		)
		(fp_line
			(start -0.8636 -0.4064)
			(end -1.1938 -0.4064)
			(stroke
				(width 0.1)
				(type default)
			)
			(layer "B.Fab")
		)
		(fp_line
			(start -1.1938 -0.4064)
			(end -1.1938 0.4064)
			(stroke
				(width 0.1)
				(type default)
			)
			(layer "B.Fab")
		)
		(fp_line
			(start 1.1938 0.4064)
			(end 1.1938 -0.4064)
			(stroke
				(width 0.1)
				(type default)
			)
			(layer "B.Fab")
		)
		(fp_line
			(start 0.8636 0.4064)
			(end 1.1938 0.4064)
			(stroke
				(width 0.1)
				(type default)
			)
			(layer "B.Fab")
		)
		(fp_line
			(start -0.8636 0.4064)
			(end -0.8636 0.4572)
			(stroke
				(width 0.1)
				(type default)
			)
			(layer "B.Fab")
		)
		(fp_line
			(start -1.1938 0.4064)
			(end -0.8636 0.4064)
			(stroke
				(width 0.1)
				(type default)
			)
			(layer "B.Fab")
		)
		(fp_line
			(start 0.8636 0.4572)
			(end 0.8636 0.4064)
			(stroke
				(width 0.1)
				(type default)
			)
			(layer "B.Fab")
		)
		(fp_line
			(start -0.8636 0.4572)
			(end 0.8636 0.4572)
			(stroke
				(width 0.1)
				(type default)
			)
			(layer "B.Fab")
		)
		(pad "1" smd rect
			(at 0.7366 0)
			(size 0.7112 0.8128)
			(layers "B.Cu" "B.Mask" "B.Paste")
			(net "P0V8_SERDES_VDDA_PEX1")
		)
		(pad "2" smd rect
			(at -0.7366 0)
			(size 0.7112 0.8128)
			(layers "B.Cu" "B.Mask" "B.Paste")
			(net "GND")
		)
	)
	(footprint ""
		(layer "B.Cu")
		(at 358.604566 -285.607506 -90)
		(property "Reference" "PR7182"
			(at 0 0 90)
			(layer "B.SilkS")
			(hide yes)
			(effects
				(font
					(size 1.27 1.27)
				)
				(justify mirror)
			)
		)
		(property "Value" ""
			(at 0 0 90)
			(layer "B.Fab")
			(effects
				(font
					(size 1.27 1.27)
				)
				(justify mirror)
			)
		)
		(duplicate_pad_numbers_are_jumpers no)
		(fp_line
			(start -0.7874 0.4064)
			(end 0.7874 0.4064)
			(stroke
				(width 0.1524)
				(type default)
			)
			(layer "B.SilkS")
		)
		(fp_line
			(start 0.7874 0.4064)
			(end 0.7874 -0.4064)
			(stroke
				(width 0.1524)
				(type default)
			)
			(layer "B.SilkS")
		)
		(fp_line
			(start -0.7874 -0.4064)
			(end -0.7874 0.4064)
			(stroke
				(width 0.1524)
				(type default)
			)
			(layer "B.SilkS")
		)
		(fp_line
			(start 0.7874 -0.4064)
			(end -0.7874 -0.4064)
			(stroke
				(width 0.1524)
				(type default)
			)
			(layer "B.SilkS")
		)
		(fp_line
			(start -0.67945 0.3048)
			(end -0.120396 0.3048)
			(stroke
				(width 0.1)
				(type default)
			)
			(layer "B.Fab")
		)
		(fp_line
			(start -0.120396 0.3048)
			(end -0.120396 0.2794)
			(stroke
				(width 0.1)
				(type default)
			)
			(layer "B.Fab")
		)
		(fp_line
			(start 0.12065 0.3048)
			(end 0.67945 0.3048)
			(stroke
				(width 0.1)
				(type default)
			)
			(layer "B.Fab")
		)
		(fp_line
			(start 0.67945 0.3048)
			(end 0.67945 -0.305054)
			(stroke
				(width 0.1)
				(type default)
			)
			(layer "B.Fab")
		)
		(fp_line
			(start -0.120396 0.2794)
			(end 0.12065 0.2794)
			(stroke
				(width 0.1)
				(type default)
			)
			(layer "B.Fab")
		)
		(fp_line
			(start 0.12065 0.2794)
			(end 0.12065 0.3048)
			(stroke
				(width 0.1)
				(type default)
			)
			(layer "B.Fab")
		)
		(fp_line
			(start -0.12065 -0.2794)
			(end -0.12065 -0.3048)
			(stroke
				(width 0.1)
				(type default)
			)
			(layer "B.Fab")
		)
		(fp_line
			(start 0.12065 -0.2794)
			(end -0.12065 -0.2794)
			(stroke
				(width 0.1)
				(type default)
			)
			(layer "B.Fab")
		)
		(fp_line
			(start -0.67945 -0.3048)
			(end -0.67945 0.3048)
			(stroke
				(width 0.1)
				(type default)
			)
			(layer "B.Fab")
		)
		(fp_line
			(start -0.12065 -0.3048)
			(end -0.67945 -0.3048)
			(stroke
				(width 0.1)
				(type default)
			)
			(layer "B.Fab")
		)
		(fp_line
			(start 0.12065 -0.305054)
			(end 0.12065 -0.2794)
			(stroke
				(width 0.1)
				(type default)
			)
			(layer "B.Fab")
		)
		(fp_line
			(start 0.67945 -0.305054)
			(end 0.12065 -0.305054)
			(stroke
				(width 0.1)
				(type default)
			)
			(layer "B.Fab")
		)
		(pad "1" smd circle
			(at 0.40005 0 90)
			(size 0 0)
			(layers "B.Cu" "B.Mask" "B.Paste")
			(net "P0V8_PEX3_PVCC")
		)
		(pad "2" smd circle
			(at -0.40005 0 90)
			(size 0 0)
			(layers "B.Cu" "B.Mask" "B.Paste")
			(net "P5V_AUX")
		)
	)
	(footprint ""
		(layer "B.Cu")
		(at 129.207006 -275.81606 180)
		(property "Reference" "PC6613"
			(at 0 0 0)
			(layer "B.SilkS")
			(hide yes)
			(effects
				(font
					(size 1.27 1.27)
				)
				(justify mirror)
			)
		)
		(property "Value" ""
			(at 0 0 0)
			(layer "B.Fab")
			(effects
				(font
					(size 1.27 1.27)
				)
				(justify mirror)
			)
		)
		(duplicate_pad_numbers_are_jumpers no)
		(fp_line
			(start 1.524 0.762)
			(end 1.524 -0.762)
			(stroke
				(width 0.1524)
				(type default)
			)
			(layer "B.SilkS")
		)
		(fp_line
			(start 1.524 -0.762)
			(end -1.524 -0.762)
			(stroke
				(width 0.1524)
				(type default)
			)
			(layer "B.SilkS")
		)
		(fp_line
			(start -1.524 0.762)
			(end 1.524 0.762)
			(stroke
				(width 0.1524)
				(type default)
			)
			(layer "B.SilkS")
		)
		(fp_line
			(start -1.524 -0.762)
			(end -1.524 0.762)
			(stroke
				(width 0.1524)
				(type default)
			)
			(layer "B.SilkS")
		)
		(fp_line
			(start 1.1049 0.724916)
			(end -1.1049 0.724916)
			(stroke
				(width 0.1)
				(type default)
			)
			(layer "B.Fab")
		)
		(fp_line
			(start 1.1049 -0.724916)
			(end 1.1049 0.724916)
			(stroke
				(width 0.1)
				(type default)
			)
			(layer "B.Fab")
		)
		(fp_line
			(start -1.1049 0.724916)
			(end -1.1049 -0.724916)
			(stroke
				(width 0.1)
				(type default)
			)
			(layer "B.Fab")
		)
		(fp_line
			(start -1.1049 -0.724916)
			(end 1.1049 -0.724916)
			(stroke
				(width 0.1)
				(type default)
			)
			(layer "B.Fab")
		)
		(pad "1" smd rect
			(at 0.889 0 180)
			(size 1.016 1.27)
			(layers "B.Cu" "B.Mask" "B.Paste")
			(net "SW_P12V_P0V8_PEX1_FLT")
		)
		(pad "2" smd rect
			(at -0.889 0 180)
			(size 1.016 1.27)
			(layers "B.Cu" "B.Mask" "B.Paste")
			(net "GND")
		)
	)
	(footprint ""
		(layer "B.Cu")
		(at 234.74553 -275.632672)
		(property "Reference" "C4331"
			(at 0 0 0)
			(layer "B.SilkS")
			(hide yes)
			(effects
				(font
					(size 1.27 1.27)
				)
				(justify mirror)
			)
		)
		(property "Value" ""
			(at 0 0 0)
			(layer "B.Fab")
			(effects
				(font
					(size 1.27 1.27)
				)
				(justify mirror)
			)
		)
		(duplicate_pad_numbers_are_jumpers no)
		(fp_line
			(start -1.2954 -0.5842)
			(end -1.2954 0.5842)
			(stroke
				(width 0.1524)
				(type default)
			)
			(layer "B.SilkS")
		)
		(fp_line
			(start -1.2954 0.5842)
			(end 1.2954 0.5842)
			(stroke
				(width 0.1524)
				(type default)
			)
			(layer "B.SilkS")
		)
		(fp_line
			(start 1.2954 -0.5842)
			(end -1.2954 -0.5842)
			(stroke
				(width 0.1524)
				(type default)
			)
			(layer "B.SilkS")
		)
		(fp_line
			(start 1.2954 0.5842)
			(end 1.2954 -0.5842)
			(stroke
				(width 0.1524)
				(type default)
			)
			(layer "B.SilkS")
		)
		(fp_line
			(start -1.1938 -0.4064)
			(end -1.1938 0.4064)
			(stroke
				(width 0.1)
				(type default)
			)
			(layer "B.Fab")
		)
		(fp_line
			(start -1.1938 0.4064)
			(end -0.8636 0.4064)
			(stroke
				(width 0.1)
				(type default)
			)
			(layer "B.Fab")
		)
		(fp_line
			(start -0.8636 -0.4572)
			(end -0.8636 -0.4064)
			(stroke
				(width 0.1)
				(type default)
			)
			(layer "B.Fab")
		)
		(fp_line
			(start -0.8636 -0.4064)
			(end -1.1938 -0.4064)
			(stroke
				(width 0.1)
				(type default)
			)
			(layer "B.Fab")
		)
		(fp_line
			(start -0.8636 0.4064)
			(end -0.8636 0.4572)
			(stroke
				(width 0.1)
				(type default)
			)
			(layer "B.Fab")
		)
		(fp_line
			(start -0.8636 0.4572)
			(end 0.8636 0.4572)
			(stroke
				(width 0.1)
				(type default)
			)
			(layer "B.Fab")
		)
		(fp_line
			(start 0.8636 -0.4572)
			(end -0.8636 -0.4572)
			(stroke
				(width 0.1)
				(type default)
			)
			(layer "B.Fab")
		)
		(fp_line
			(start 0.8636 -0.4064)
			(end 0.8636 -0.4572)
			(stroke
				(width 0.1)
				(type default)
			)
			(layer "B.Fab")
		)
		(fp_line
			(start 0.8636 0.4064)
			(end 1.1938 0.4064)
			(stroke
				(width 0.1)
				(type default)
			)
			(layer "B.Fab")
		)
		(fp_line
			(start 0.8636 0.4572)
			(end 0.8636 0.4064)
			(stroke
				(width 0.1)
				(type default)
			)
			(layer "B.Fab")
		)
		(fp_line
			(start 1.1938 -0.4064)
			(end 0.8636 -0.4064)
			(stroke
				(width 0.1)
				(type default)
			)
			(layer "B.Fab")
		)
		(fp_line
			(start 1.1938 0.4064)
			(end 1.1938 -0.4064)
			(stroke
				(width 0.1)
				(type default)
			)
			(layer "B.Fab")
		)
		(pad "1" smd rect
			(at 0.7366 0 270)
			(size 0.7112 0.8128)
			(layers "B.Cu" "B.Mask" "B.Paste")
			(net "P1V25_PEX2")
		)
		(pad "2" smd rect
			(at -0.7366 0 270)
			(size 0.7112 0.8128)
			(layers "B.Cu" "B.Mask" "B.Paste")
			(net "GND")
		)
	)
)
